# SCM (Grand Teton) — schematic netlist excerpt (pin names and nets, part order shuffled) for the footprints in the layout excerpt that follows; sources: Cadence DE-HDL packaged netlist, KiCad conversion of 12092022_DA0F0TMDCD0_F0T_Management_Board_D_brd_V3_OCP.brd

C208  Q_CAP  22PF 50V 5% NPO  pkg 0402  page 23 : A = V_DACR_IO ; B = GND
R152  Q_RES  33.2 1% CHIP  pkg 0402LF  page 12 : A = SMB_BMC_MM16_SCL ; B = SMB_BMC_MM16_R_SCL

(kicad_pcb
	(version 20260206)
	(generator "pcbnew")
	(generator_version "10.0")
	(general
		(thickness 1.6)
		(legacy_teardrops no)
	)
	(paper "A4")
	(title_block
		(title "12092022_DA0F0TMDCD0_F0T_Management_Board_D_brd_V3_OCP.brd")
		(comment 1 "Grand Teton / footprints 1141-1142 of 1440")
	)
	(layers
		(0 "F.Cu" signal "TOP")
		(4 "In1.Cu" signal "GND")
		(6 "In2.Cu" signal "IN1")
		(8 "In3.Cu" signal "GND1")
		(10 "In4.Cu" signal "IN2")
		(12 "In5.Cu" signal "VCC")
		(14 "In6.Cu" signal "VCC1")
		(16 "In7.Cu" signal "IN3")
		(18 "In8.Cu" signal "GND2")
		(20 "In9.Cu" signal "IN4")
		(22 "In10.Cu" signal "GND3")
		(2 "B.Cu" signal "BOTTOM")
		(9 "F.Adhes" user "F.Adhesive")
		(11 "B.Adhes" user "B.Adhesive")
		(13 "F.Paste" user "Package Geometry/Pastemask Top")
		(15 "B.Paste" user "Package Geometry/Pastemask Bottom")
		(5 "F.SilkS" user "Ref Des/Silkscreen Top")
		(7 "B.SilkS" user "Ref Des/Silkscreen Bottom")
		(1 "F.Mask" user "Board Geometry/Soldermask Top")
		(3 "B.Mask" user "Board Geometry/Soldermask Bottom")
		(17 "Dwgs.User" user "User.Drawings")
		(19 "Cmts.User" user "User.Comments")
		(21 "Eco1.User" user "User.Eco1")
		(23 "Eco2.User" user "User.Eco2")
		(25 "Edge.Cuts" user "Board Geometry/Outline")
		(27 "Margin" user)
		(31 "F.CrtYd" user "Package Geometry/Place Bound Top")
		(29 "B.CrtYd" user "Package Geometry/Place Bound Bottom")
		(35 "F.Fab" user "Ref Des/Assembly Top")
		(33 "B.Fab" user "Ref Des/Assembly Bottom")
	)
	(footprint ""
		(layer "B.Cu")
		(at 50.546 -34.6456 -90)
		(property "Reference" "R152"
			(at 0 0 90)
			(layer "B.SilkS")
			(hide yes)
			(effects
				(font
					(size 1.27 1.27)
				)
				(justify mirror)
			)
		)
		(property "Value" ""
			(at 0 0 90)
			(layer "B.Fab")
			(effects
				(font
					(size 1.27 1.27)
				)
				(justify mirror)
			)
		)
		(duplicate_pad_numbers_are_jumpers no)
		(fp_line
			(start -0.7874 0.4064)
			(end 0.7874 0.4064)
			(stroke
				(width 0.1524)
				(type default)
			)
			(layer "B.SilkS")
		)
		(fp_line
			(start 0.7874 0.4064)
			(end 0.7874 -0.4064)
			(stroke
				(width 0.1524)
				(type default)
			)
			(layer "B.SilkS")
		)
		(fp_line
			(start -0.7874 -0.4064)
			(end -0.7874 0.4064)
			(stroke
				(width 0.1524)
				(type default)
			)
			(layer "B.SilkS")
		)
		(fp_line
			(start 0.7874 -0.4064)
			(end -0.7874 -0.4064)
			(stroke
				(width 0.1524)
				(type default)
			)
			(layer "B.SilkS")
		)
		(fp_line
			(start -0.67945 0.3048)
			(end -0.120396 0.3048)
			(stroke
				(width 0.1)
				(type default)
			)
			(layer "B.Fab")
		)
		(fp_line
			(start -0.120396 0.3048)
			(end -0.120396 0.2794)
			(stroke
				(width 0.1)
				(type default)
			)
			(layer "B.Fab")
		)
		(fp_line
			(start 0.12065 0.3048)
			(end 0.67945 0.3048)
			(stroke
				(width 0.1)
				(type default)
			)
			(layer "B.Fab")
		)
		(fp_line
			(start 0.67945 0.3048)
			(end 0.67945 -0.305054)
			(stroke
				(width 0.1)
				(type default)
			)
			(layer "B.Fab")
		)
		(fp_line
			(start -0.120396 0.2794)
			(end 0.12065 0.2794)
			(stroke
				(width 0.1)
				(type default)
			)
			(layer "B.Fab")
		)
		(fp_line
			(start 0.12065 0.2794)
			(end 0.12065 0.3048)
			(stroke
				(width 0.1)
				(type default)
			)
			(layer "B.Fab")
		)
		(fp_line
			(start -0.12065 -0.2794)
			(end -0.12065 -0.3048)
			(stroke
				(width 0.1)
				(type default)
			)
			(layer "B.Fab")
		)
		(fp_line
			(start 0.12065 -0.2794)
			(end -0.12065 -0.2794)
			(stroke
				(width 0.1)
				(type default)
			)
			(layer "B.Fab")
		)
		(fp_line
			(start -0.67945 -0.3048)
			(end -0.67945 0.3048)
			(stroke
				(width 0.1)
				(type default)
			)
			(layer "B.Fab")
		)
		(fp_line
			(start -0.12065 -0.3048)
			(end -0.67945 -0.3048)
			(stroke
				(width 0.1)
				(type default)
			)
			(layer "B.Fab")
		)
		(fp_line
			(start 0.12065 -0.305054)
			(end 0.12065 -0.2794)
			(stroke
				(width 0.1)
				(type default)
			)
			(layer "B.Fab")
		)
		(fp_line
			(start 0.67945 -0.305054)
			(end 0.12065 -0.305054)
			(stroke
				(width 0.1)
				(type default)
			)
			(layer "B.Fab")
		)
		(pad "1" smd circle
			(at 0.40005 0 90)
			(size 0 0)
			(layers "B.Cu" "B.Mask" "B.Paste")
			(net "SMB_BMC_MM16_SCL")
		)
		(pad "2" smd circle
			(at -0.40005 0 90)
			(size 0 0)
			(layers "B.Cu" "B.Mask" "B.Paste")
			(net "SMB_BMC_MM16_R_SCL")
		)
	)
	(footprint ""
		(layer "B.Cu")
		(at 31.369 -32.131 90)
		(property "Reference" "C208"
			(at 0 0 90)
			(layer "B.SilkS")
			(hide yes)
			(effects
				(font
					(size 1.27 1.27)
				)
				(justify mirror)
			)
		)
		(property "Value" ""
			(at 0 0 90)
			(layer "B.Fab")
			(effects
				(font
					(size 1.27 1.27)
				)
				(justify mirror)
			)
		)
		(duplicate_pad_numbers_are_jumpers no)
		(fp_line
			(start 0.7874 -0.4064)
			(end -0.7874 -0.4064)
			(stroke
				(width 0.1524)
				(type default)
			)
			(layer "B.SilkS")
		)
		(fp_line
			(start -0.7874 -0.4064)
			(end -0.7874 0.4064)
			(stroke
				(width 0.1524)
				(type default)
			)
			(layer "B.SilkS")
		)
		(fp_line
			(start 0.7874 0.4064)
			(end 0.7874 -0.4064)
			(stroke
				(width 0.1524)
				(type default)
			)
			(layer "B.SilkS")
		)
		(fp_line
			(start -0.7874 0.4064)
			(end 0.7874 0.4064)
			(stroke
				(width 0.1524)
				(type default)
			)
			(layer "B.SilkS")
		)
		(fp_line
			(start 0.67945 -0.305054)
			(end 0.12065 -0.305054)
			(stroke
				(width 0.1)
				(type default)
			)
			(layer "B.Fab")
		)
		(fp_line
			(start 0.12065 -0.305054)
			(end 0.12065 -0.2794)
			(stroke
				(width 0.1)
				(type default)
			)
			(layer "B.Fab")
		)
		(fp_line
			(start -0.12065 -0.3048)
			(end -0.67945 -0.3048)
			(stroke
				(width 0.1)
				(type default)
			)
			(layer "B.Fab")
		)
		(fp_line
			(start -0.67945 -0.3048)
			(end -0.67945 0.3048)
			(stroke
				(width 0.1)
				(type default)
			)
			(layer "B.Fab")
		)
		(fp_line
			(start 0.12065 -0.2794)
			(end -0.12065 -0.2794)
			(stroke
				(width 0.1)
				(type default)
			)
			(layer "B.Fab")
		)
		(fp_line
			(start -0.12065 -0.2794)
			(end -0.12065 -0.3048)
			(stroke
				(width 0.1)
				(type default)
			)
			(layer "B.Fab")
		)
		(fp_line
			(start 0.12065 0.2794)
			(end 0.12065 0.3048)
			(stroke
				(width 0.1)
				(type default)
			)
			(layer "B.Fab")
		)
		(fp_line
			(start -0.120396 0.2794)
			(end 0.12065 0.2794)
			(stroke
				(width 0.1)
				(type default)
			)
			(layer "B.Fab")
		)
		(fp_line
			(start 0.67945 0.3048)
			(end 0.67945 -0.305054)
			(stroke
				(width 0.1)
				(type default)
			)
			(layer "B.Fab")
		)
		(fp_line
			(start 0.12065 0.3048)
			(end 0.67945 0.3048)
			(stroke
				(width 0.1)
				(type default)
			)
			(layer "B.Fab")
		)
		(fp_line
			(start -0.120396 0.3048)
			(end -0.120396 0.2794)
			(stroke
				(width 0.1)
				(type default)
			)
			(layer "B.Fab")
		)
		(fp_line
			(start -0.67945 0.3048)
			(end -0.120396 0.3048)
			(stroke
				(width 0.1)
				(type default)
			)
			(layer "B.Fab")
		)
		(pad "1" smd circle
			(at 0.40005 0 270)
			(size 0 0)
			(layers "B.Cu" "B.Mask" "B.Paste")
			(net "V_DACR_IO")
		)
		(pad "2" smd circle
			(at -0.40005 0 270)
			(size 0 0)
			(layers "B.Cu" "B.Mask" "B.Paste")
			(net "GND")
		)
	)
)
